(kicad_pcb
	(version 20260206)
	(generator "pcbnew")
	(generator_version "10.0")
	(general
		(thickness 1.6)
		(legacy_teardrops no)
	)
	(paper "A4")
	(title_block
		(title "Bryce Canyon_SCC_16316-1_OCP.brd")
		(comment 1 "Bryce Canyon / footprints 1001-1009 of 1561")
	)
	(layers
		(0 "F.Cu" signal "TOP")
		(4 "In1.Cu" signal "L2GND")
		(6 "In2.Cu" signal "L3")
		(8 "In3.Cu" signal "L4VCC")
		(10 "In4.Cu" signal "L5VCC")
		(12 "In5.Cu" signal "L6")
		(14 "In6.Cu" signal "L7GND")
		(2 "B.Cu" signal "BOTTOM")
		(9 "F.Adhes" user "F.Adhesive")
		(11 "B.Adhes" user "B.Adhesive")
		(13 "F.Paste" user "Package Geometry/Pastemask Top")
		(15 "B.Paste" user "Package Geometry/Pastemask Bottom")
		(5 "F.SilkS" user "Ref Des/Silkscreen Top")
		(7 "B.SilkS" user "Ref Des/Silkscreen Bottom")
		(1 "F.Mask" user "Board Geometry/Soldermask Top")
		(3 "B.Mask" user "Board Geometry/Soldermask Bottom")
		(17 "Dwgs.User" user "User.Drawings")
		(19 "Cmts.User" user "User.Comments")
		(21 "Eco1.User" user "User.Eco1")
		(23 "Eco2.User" user "User.Eco2")
		(25 "Edge.Cuts" user "Board Geometry/Outline")
		(27 "Margin" user)
		(31 "F.CrtYd" user "Package Geometry/Place Bound Top")
		(29 "B.CrtYd" user "Package Geometry/Place Bound Bottom")
		(35 "F.Fab" user "Ref Des/Assembly Top")
		(33 "B.Fab" user "Ref Des/Assembly Bottom")
	)
	(footprint ""
		(layer "B.Cu")
		(at 185.2676 -28.3972)
		(property "Reference" "TP115"
			(at 0 0 0)
			(layer "B.SilkS")
			(hide yes)
			(effects
				(font
					(size 1.27 1.27)
				)
				(justify mirror)
			)
		)
		(property "Value" "TPAD28-2-GP"
			(at 0.0127 -1.6637 0)
			(unlocked yes)
			(layer "B.Fab")
			(hide yes)
			(effects
				(font
					(size 1.016 1.016)
					(thickness 0.1524)
				)
				(justify mirror)
			)
		)
		(property "Device Type" "TPAD28"
			(at 0.0127 -3.1877 0)
			(unlocked yes)
			(layer "B.Fab")
			(hide yes)
			(effects
				(font
					(size 1.016 1.016)
					(thickness 0.1524)
				)
				(justify mirror)
			)
		)
		(duplicate_pad_numbers_are_jumpers no)
		(fp_poly
			(pts
				(arc
					(start 0.3556 0)
					(mid -0.3556 0)
					(end 0.3556 0)
				)
			)
			(stroke
				(width 0)
				(type default)
			)
			(fill no)
			(layer "B.CrtYd")
		)
		(fp_poly
			(pts
				(arc
					(start 0.6096 0)
					(mid -0.6096 0)
					(end 0.6096 0)
				)
			)
			(stroke
				(width 0)
				(type default)
			)
			(fill no)
			(layer "B.Fab")
		)
		(pad "1" smd circle
			(at 0 0 180)
			(size 0.7112 0.7112)
			(layers "B.Cu" "B.Mask" "B.Paste")
			(net "IOC_UART_1_RX")
		)
	)
	(footprint ""
		(layer "B.Cu")
		(at 112.498632 -74.497692)
		(property "Reference" "TP46"
			(at 0 0 0)
			(layer "B.SilkS")
			(hide yes)
			(effects
				(font
					(size 1.27 1.27)
				)
				(justify mirror)
			)
		)
		(property "Value" "TPAD28-2-GP"
			(at 0.0127 -1.6637 0)
			(unlocked yes)
			(layer "B.Fab")
			(hide yes)
			(effects
				(font
					(size 1.016 1.016)
					(thickness 0.1524)
				)
				(justify mirror)
			)
		)
		(property "Device Type" "TPAD28"
			(at 0.0127 -3.1877 0)
			(unlocked yes)
			(layer "B.Fab")
			(hide yes)
			(effects
				(font
					(size 1.016 1.016)
					(thickness 0.1524)
				)
				(justify mirror)
			)
		)
		(duplicate_pad_numbers_are_jumpers no)
		(fp_poly
			(pts
				(arc
					(start 0.3556 0)
					(mid -0.3556 0)
					(end 0.3556 0)
				)
			)
			(stroke
				(width 0)
				(type default)
			)
			(fill no)
			(layer "B.CrtYd")
		)
		(fp_poly
			(pts
				(arc
					(start 0.6096 0)
					(mid -0.6096 0)
					(end 0.6096 0)
				)
			)
			(stroke
				(width 0)
				(type default)
			)
			(fill no)
			(layer "B.Fab")
		)
		(pad "1" smd circle
			(at 0 0 180)
			(size 0.7112 0.7112)
			(layers "B.Cu" "B.Mask" "B.Paste")
			(net "EXP_XM_ADDR_24")
		)
	)
	(footprint ""
		(layer "B.Cu")
		(at 110.236 -81.8388)
		(property "Reference" "TP51"
			(at 0 0 0)
			(layer "B.SilkS")
			(hide yes)
			(effects
				(font
					(size 1.27 1.27)
				)
				(justify mirror)
			)
		)
		(property "Value" "TPAD28-2-GP"
			(at 0.0127 -1.6637 0)
			(unlocked yes)
			(layer "B.Fab")
			(hide yes)
			(effects
				(font
					(size 1.016 1.016)
					(thickness 0.1524)
				)
				(justify mirror)
			)
		)
		(property "Device Type" "TPAD28"
			(at 0.0127 -3.1877 0)
			(unlocked yes)
			(layer "B.Fab")
			(hide yes)
			(effects
				(font
					(size 1.016 1.016)
					(thickness 0.1524)
				)
				(justify mirror)
			)
		)
		(duplicate_pad_numbers_are_jumpers no)
		(fp_poly
			(pts
				(arc
					(start 0.3556 0)
					(mid -0.3556 0)
					(end 0.3556 0)
				)
			)
			(stroke
				(width 0)
				(type default)
			)
			(fill no)
			(layer "B.CrtYd")
		)
		(fp_poly
			(pts
				(arc
					(start 0.6096 0)
					(mid -0.6096 0)
					(end 0.6096 0)
				)
			)
			(stroke
				(width 0)
				(type default)
			)
			(fill no)
			(layer "B.Fab")
		)
		(pad "1" smd circle
			(at 0 0 180)
			(size 0.7112 0.7112)
			(layers "B.Cu" "B.Mask" "B.Paste")
			(net "XM_WBE_1#_TP")
		)
	)
	(footprint ""
		(layer "B.Cu")
		(at 166.627302 -42.399966 90)
		(property "Reference" "R255"
			(at 0 0 90)
			(layer "B.SilkS")
			(hide yes)
			(effects
				(font
					(size 1.27 1.27)
				)
				(justify mirror)
			)
		)
		(property "Value" "10KR2F-2-GP"
			(at -0.064008 -3.993896 90)
			(unlocked yes)
			(layer "B.Fab")
			(hide yes)
			(effects
				(font
					(size 1.016 1.016)
					(thickness 0.1524)
				)
				(justify mirror)
			)
		)
		(property "Device Type" "R402H16"
			(at -0.064008 -5.517896 90)
			(unlocked yes)
			(layer "B.Fab")
			(hide yes)
			(effects
				(font
					(size 1.016 1.016)
					(thickness 0.1524)
				)
				(justify mirror)
			)
		)
		(duplicate_pad_numbers_are_jumpers no)
		(fp_line
			(start 0.508 -0.9398)
			(end 0.508 0.9398)
			(stroke
				(width 0.1524)
				(type default)
			)
			(layer "B.SilkS")
		)
		(fp_line
			(start -0.508 -0.9398)
			(end 0.508 -0.9398)
			(stroke
				(width 0.1524)
				(type default)
			)
			(layer "B.SilkS")
		)
		(fp_rect
			(start 0.508 0.9398)
			(end -0.508 -0.9398)
			(stroke
				(width 0)
				(type default)
			)
			(fill no)
			(layer "B.CrtYd")
		)
		(fp_rect
			(start 0.508 0.9398)
			(end -0.508 -0.9398)
			(stroke
				(width 0)
				(type default)
			)
			(fill no)
			(layer "B.Fab")
		)
		(pad "1" smd custom
			(at 0 -0.4445 270)
			(size 0.1397 0.1397)
			(layers "B.Cu" "B.Mask" "B.Paste")
			(net "P1V8_C")
			(options
				(clearance outline)
				(anchor circle)
			)
			(primitives
				(gr_poly
					(pts
						(arc
							(start -0.1778 0.2794)
							(mid -0.249642 0.249642)
							(end -0.2794 0.1778)
						)
						(arc
							(start -0.2794 -0.1778)
							(mid -0.249642 -0.249642)
							(end -0.1778 -0.2794)
						)
						(arc
							(start 0.1778 -0.2794)
							(mid 0.249642 -0.249642)
							(end 0.2794 -0.1778)
						)
						(arc
							(start 0.2794 0.1778)
							(mid 0.249642 0.249642)
							(end 0.1778 0.2794)
						)
					)
					(width 0)
					(fill yes)
				)
			)
		)
		(pad "2" smd custom
			(at 0 0.4445 270)
			(size 0.1397 0.1397)
			(layers "B.Cu" "B.Mask" "B.Paste")
			(net "POWERLOSS#")
			(options
				(clearance outline)
				(anchor circle)
			)
			(primitives
				(gr_poly
					(pts
						(arc
							(start -0.1778 0.2794)
							(mid -0.249642 0.249642)
							(end -0.2794 0.1778)
						)
						(arc
							(start -0.2794 -0.1778)
							(mid -0.249642 -0.249642)
							(end -0.1778 -0.2794)
						)
						(arc
							(start 0.1778 -0.2794)
							(mid 0.249642 -0.249642)
							(end 0.2794 -0.1778)
						)
						(arc
							(start 0.2794 0.1778)
							(mid 0.249642 0.249642)
							(end 0.1778 0.2794)
						)
					)
					(width 0)
					(fill yes)
				)
			)
		)
	)
	(footprint ""
		(layer "B.Cu")
		(at 137.2108 -89.6874)
		(property "Reference" "R57"
			(at 0 0 0)
			(layer "B.SilkS")
			(hide yes)
			(effects
				(font
					(size 1.27 1.27)
				)
				(justify mirror)
			)
		)
		(property "Value" "4K7R2F-GP"
			(at -0.064008 -3.993896 0)
			(unlocked yes)
			(layer "B.Fab")
			(hide yes)
			(effects
				(font
					(size 1.016 1.016)
					(thickness 0.1524)
				)
				(justify mirror)
			)
		)
		(property "Device Type" "R402H16"
			(at -0.064008 -5.517896 0)
			(unlocked yes)
			(layer "B.Fab")
			(hide yes)
			(effects
				(font
					(size 1.016 1.016)
					(thickness 0.1524)
				)
				(justify mirror)
			)
		)
		(duplicate_pad_numbers_are_jumpers no)
		(fp_line
			(start -0.508 -0.9398)
			(end 0.508 -0.9398)
			(stroke
				(width 0.1524)
				(type default)
			)
			(layer "B.SilkS")
		)
		(fp_line
			(start 0.508 -0.9398)
			(end 0.508 0.9398)
			(stroke
				(width 0.1524)
				(type default)
			)
			(layer "B.SilkS")
		)
		(fp_rect
			(start 0.508 0.9398)
			(end -0.508 -0.9398)
			(stroke
				(width 0)
				(type default)
			)
			(fill no)
			(layer "B.CrtYd")
		)
		(fp_rect
			(start 0.508 0.9398)
			(end -0.508 -0.9398)
			(stroke
				(width 0)
				(type default)
			)
			(fill no)
			(layer "B.Fab")
		)
		(pad "1" smd custom
			(at 0 -0.4445 180)
			(size 0.1397 0.1397)
			(layers "B.Cu" "B.Mask" "B.Paste")
			(net "P1V8_E")
			(options
				(clearance outline)
				(anchor circle)
			)
			(primitives
				(gr_poly
					(pts
						(arc
							(start -0.1778 0.2794)
							(mid -0.249642 0.249642)
							(end -0.2794 0.1778)
						)
						(arc
							(start -0.2794 -0.1778)
							(mid -0.249642 -0.249642)
							(end -0.1778 -0.2794)
						)
						(arc
							(start 0.1778 -0.2794)
							(mid 0.249642 -0.249642)
							(end 0.2794 -0.1778)
						)
						(arc
							(start 0.2794 0.1778)
							(mid 0.249642 0.249642)
							(end 0.1778 0.2794)
						)
					)
					(width 0)
					(fill yes)
				)
			)
		)
		(pad "2" smd custom
			(at 0 0.4445 180)
			(size 0.1397 0.1397)
			(layers "B.Cu" "B.Mask" "B.Paste")
			(net "I2C_DRIVE_PWR_SDA4_LS")
			(options
				(clearance outline)
				(anchor circle)
			)
			(primitives
				(gr_poly
					(pts
						(arc
							(start -0.1778 0.2794)
							(mid -0.249642 0.249642)
							(end -0.2794 0.1778)
						)
						(arc
							(start -0.2794 -0.1778)
							(mid -0.249642 -0.249642)
							(end -0.1778 -0.2794)
						)
						(arc
							(start 0.1778 -0.2794)
							(mid 0.249642 -0.249642)
							(end 0.2794 -0.1778)
						)
						(arc
							(start 0.2794 0.1778)
							(mid 0.249642 0.249642)
							(end 0.1778 0.2794)
						)
					)
					(width 0)
					(fill yes)
				)
			)
		)
	)
	(footprint ""
		(layer "B.Cu")
		(at 113.3856 -59.4487)
		(property "Reference" "C284"
			(at 0 0 0)
			(layer "B.SilkS")
			(hide yes)
			(effects
				(font
					(size 1.27 1.27)
				)
				(justify mirror)
			)
		)
		(property "Value" "SCD1U6D3V1KX-GP"
			(at 2.8321 -1.7399 0)
			(unlocked yes)
			(layer "B.Fab")
			(hide yes)
			(effects
				(font
					(size 1.016 1.016)
					(thickness 0.1524)
				)
				(justify mirror)
			)
		)
		(property "Device Type" "C0201H13"
			(at 2.8321 -3.2639 0)
			(unlocked yes)
			(layer "B.Fab")
			(hide yes)
			(effects
				(font
					(size 1.016 1.016)
					(thickness 0.1524)
				)
				(justify mirror)
			)
		)
		(duplicate_pad_numbers_are_jumpers no)
		(fp_rect
			(start 0.2794 0.6477)
			(end -0.2794 -0.6477)
			(stroke
				(width 0)
				(type default)
			)
			(fill no)
			(layer "B.CrtYd")
		)
		(fp_rect
			(start 0.2794 0.6477)
			(end -0.2794 -0.6477)
			(stroke
				(width 0)
				(type default)
			)
			(fill no)
			(layer "B.Fab")
		)
		(pad "1" smd custom
			(at 0 -0.2794 180)
			(size 0.0762 0.0762)
			(layers "B.Cu" "B.Mask" "B.Paste")
			(net "GB_VDDA")
			(options
				(clearance outline)
				(anchor circle)
			)
			(primitives
				(gr_poly
					(pts
						(arc
							(start 0.1524 0.127)
							(mid 0.137521 0.162921)
							(end 0.1016 0.1778)
						)
						(arc
							(start -0.1016 0.1778)
							(mid -0.137521 0.162921)
							(end -0.1524 0.127)
						)
						(arc
							(start -0.1524 -0.127)
							(mid -0.137521 -0.162921)
							(end -0.1016 -0.1778)
						)
						(arc
							(start 0.1016 -0.1778)
							(mid 0.137521 -0.162921)
							(end 0.1524 -0.127)
						)
					)
					(width 0)
					(fill yes)
				)
			)
		)
		(pad "2" smd custom
			(at 0 0.2794 180)
			(size 0.0762 0.0762)
			(layers "B.Cu" "B.Mask" "B.Paste")
			(net "GND")
			(options
				(clearance outline)
				(anchor circle)
			)
			(primitives
				(gr_poly
					(pts
						(arc
							(start 0.1524 0.127)
							(mid 0.137521 0.162921)
							(end 0.1016 0.1778)
						)
						(arc
							(start -0.1016 0.1778)
							(mid -0.137521 0.162921)
							(end -0.1524 0.127)
						)
						(arc
							(start -0.1524 -0.127)
							(mid -0.137521 -0.162921)
							(end -0.1016 -0.1778)
						)
						(arc
							(start 0.1016 -0.1778)
							(mid 0.137521 -0.162921)
							(end 0.1524 -0.127)
						)
					)
					(width 0)
					(fill yes)
				)
			)
		)
	)
	(footprint ""
		(layer "B.Cu")
		(at 100.5332 -58.4962 -90)
		(property "Reference" "C136"
			(at 0 0 90)
			(layer "B.SilkS")
			(hide yes)
			(effects
				(font
					(size 1.27 1.27)
				)
				(justify mirror)
			)
		)
		(property "Value" "SCD1U6D3V1KX-GP"
			(at 2.8321 -1.7399 270)
			(unlocked yes)
			(layer "B.Fab")
			(hide yes)
			(effects
				(font
					(size 1.016 1.016)
					(thickness 0.1524)
				)
				(justify mirror)
			)
		)
		(property "Device Type" "C0201H13"
			(at 2.8321 -3.2639 270)
			(unlocked yes)
			(layer "B.Fab")
			(hide yes)
			(effects
				(font
					(size 1.016 1.016)
					(thickness 0.1524)
				)
				(justify mirror)
			)
		)
		(duplicate_pad_numbers_are_jumpers no)
		(fp_rect
			(start 0.2794 0.6477)
			(end -0.2794 -0.6477)
			(stroke
				(width 0)
				(type default)
			)
			(fill no)
			(layer "B.CrtYd")
		)
		(fp_rect
			(start 0.2794 0.6477)
			(end -0.2794 -0.6477)
			(stroke
				(width 0)
				(type default)
			)
			(fill no)
			(layer "B.Fab")
		)
		(pad "1" smd custom
			(at 0 -0.2794 90)
			(size 0.0762 0.0762)
			(layers "B.Cu" "B.Mask" "B.Paste")
			(net "P1V8_E")
			(options
				(clearance outline)
				(anchor circle)
			)
			(primitives
				(gr_poly
					(pts
						(arc
							(start 0.1524 0.127)
							(mid 0.137521 0.162921)
							(end 0.1016 0.1778)
						)
						(arc
							(start -0.1016 0.1778)
							(mid -0.137521 0.162921)
							(end -0.1524 0.127)
						)
						(arc
							(start -0.1524 -0.127)
							(mid -0.137521 -0.162921)
							(end -0.1016 -0.1778)
						)
						(arc
							(start 0.1016 -0.1778)
							(mid 0.137521 -0.162921)
							(end 0.1524 -0.127)
						)
					)
					(width 0)
					(fill yes)
				)
			)
		)
		(pad "2" smd custom
			(at 0 0.2794 90)
			(size 0.0762 0.0762)
			(layers "B.Cu" "B.Mask" "B.Paste")
			(net "GND")
			(options
				(clearance outline)
				(anchor circle)
			)
			(primitives
				(gr_poly
					(pts
						(arc
							(start 0.1524 0.127)
							(mid 0.137521 0.162921)
							(end 0.1016 0.1778)
						)
						(arc
							(start -0.1016 0.1778)
							(mid -0.137521 0.162921)
							(end -0.1524 0.127)
						)
						(arc
							(start -0.1524 -0.127)
							(mid -0.137521 -0.162921)
							(end -0.1016 -0.1778)
						)
						(arc
							(start 0.1016 -0.1778)
							(mid 0.137521 -0.162921)
							(end 0.1524 -0.127)
						)
					)
					(width 0)
					(fill yes)
				)
			)
		)
	)
	(footprint ""
		(layer "B.Cu")
		(at 171.437808 -38.33241 -90)
		(property "Reference" "C448"
			(at 0 0 90)
			(layer "B.SilkS")
			(hide yes)
			(effects
				(font
					(size 1.27 1.27)
				)
				(justify mirror)
			)
		)
		(property "Value" "SC1KP50V2KX-1GP"
			(at -1.1811 -2.7051 270)
			(unlocked yes)
			(layer "B.Fab")
			(hide yes)
			(effects
				(font
					(size 1.016 1.016)
					(thickness 0.1524)
				)
				(justify mirror)
			)
		)
		(property "Device Type" "C402H22"
			(at -1.1811 -4.2291 270)
			(unlocked yes)
			(layer "B.Fab")
			(hide yes)
			(effects
				(font
					(size 1.016 1.016)
					(thickness 0.1524)
				)
				(justify mirror)
			)
		)
		(duplicate_pad_numbers_are_jumpers no)
		(fp_rect
			(start 0.4318 0.9525)
			(end -0.4318 -0.9525)
			(stroke
				(width 0)
				(type default)
			)
			(fill no)
			(layer "B.CrtYd")
		)
		(fp_rect
			(start 0.4318 0.9525)
			(end -0.4318 -0.9525)
			(stroke
				(width 0)
				(type default)
			)
			(fill no)
			(layer "B.Fab")
		)
		(pad "1" smd custom
			(at 0 -0.4445 90)
			(size 0.1524 0.1524)
			(layers "B.Cu" "B.Mask" "B.Paste")
			(net "P0V975")
			(options
				(clearance outline)
				(anchor circle)
			)
			(primitives
				(gr_poly
					(pts
						(arc
							(start 0.3048 0.2032)
							(mid 0.275042 0.275042)
							(end 0.2032 0.3048)
						)
						(arc
							(start -0.2032 0.3048)
							(mid -0.275042 0.275042)
							(end -0.3048 0.2032)
						)
						(arc
							(start -0.3048 -0.2032)
							(mid -0.275042 -0.275042)
							(end -0.2032 -0.3048)
						)
						(arc
							(start 0.2032 -0.3048)
							(mid 0.275042 -0.275042)
							(end 0.3048 -0.2032)
						)
					)
					(width 0)
					(fill yes)
				)
			)
		)
		(pad "2" smd custom
			(at 0 0.4445 90)
			(size 0.1524 0.1524)
			(layers "B.Cu" "B.Mask" "B.Paste")
			(net "GND")
			(options
				(clearance outline)
				(anchor circle)
			)
			(primitives
				(gr_poly
					(pts
						(arc
							(start 0.3048 0.2032)
							(mid 0.275042 0.275042)
							(end 0.2032 0.3048)
						)
						(arc
							(start -0.2032 0.3048)
							(mid -0.275042 0.275042)
							(end -0.3048 0.2032)
						)
						(arc
							(start -0.3048 -0.2032)
							(mid -0.275042 -0.275042)
							(end -0.2032 -0.3048)
						)
						(arc
							(start 0.2032 -0.3048)
							(mid 0.275042 -0.275042)
							(end 0.3048 -0.2032)
						)
					)
					(width 0)
					(fill yes)
				)
			)
		)
	)
	(footprint ""
		(layer "B.Cu")
		(at 162.433 -66.802 180)
		(property "Reference" "L23"
			(at 0 0 0)
			(layer "B.SilkS")
			(hide yes)
			(effects
				(font
					(size 1.27 1.27)
				)
				(justify mirror)
			)
		)
		(property "Value" "MPZ2012S601AT-GP"
			(at 0 -4.2418 180)
			(unlocked yes)
			(layer "B.Fab")
			(hide yes)
			(effects
				(font
					(size 1.016 1.016)
					(thickness 0.1524)
				)
				(justify mirror)
			)
		)
		(property "Device Type" "L805H42"
			(at 0 -5.7912 180)
			(unlocked yes)
			(layer "B.Fab")
			(hide yes)
			(effects
				(font
					(size 1.016 1.016)
					(thickness 0.1524)
				)
				(justify mirror)
			)
		)
		(duplicate_pad_numbers_are_jumpers no)
		(fp_line
			(start 0.889 1.7018)
			(end 0.889 -1.7018)
			(stroke
				(width 0.1524)
				(type default)
			)
			(layer "B.SilkS")
		)
		(fp_line
			(start 0.889 -1.7018)
			(end -0.889 -1.7018)
			(stroke
				(width 0.1524)
				(type default)
			)
			(layer "B.SilkS")
		)
		(fp_line
			(start -0.889 1.7018)
			(end 0.889 1.7018)
			(stroke
				(width 0.1524)
				(type default)
			)
			(layer "B.SilkS")
		)
		(fp_line
			(start -0.889 -1.7018)
			(end -0.889 1.7018)
			(stroke
				(width 0.1524)
				(type default)
			)
			(layer "B.SilkS")
		)
		(fp_rect
			(start 0.9652 1.778)
			(end -0.9652 -1.778)
			(stroke
				(width 0)
				(type default)
			)
			(fill no)
			(layer "B.CrtYd")
		)
		(fp_rect
			(start 0.9652 1.778)
			(end -0.9652 -1.778)
			(stroke
				(width 0)
				(type default)
			)
			(fill no)
			(layer "B.Fab")
		)
		(pad "1" smd rect
			(at 0 -0.9652)
			(size 1.397 1.143)
			(layers "B.Cu" "B.Mask" "B.Paste")
			(net "VDDA_SAS_REF_CLK")
		)
		(pad "2" smd rect
			(at 0 0.9652)
			(size 1.397 1.143)
			(layers "B.Cu" "B.Mask" "B.Paste")
			(net "P1V8_C")
		)
	)
)
